(kicad_pcb
	(version 20260206)
	(generator "pcbnew")
	(generator_version "10.0")
	(general
		(thickness 1.6)
		(legacy_teardrops no)
	)
	(paper "A4")
	(title_block
		(title "peb — Lightning_PEB_BRD.brd")
		(comment 1 "Lightning (Wiwynn / Facebook NVMe JBOF) / footprint 139 of 2563 (CN16), pads 154-166 of 166")
	)
	(layers
		(0 "F.Cu" signal "TOP")
		(4 "In1.Cu" signal "L2GND")
		(6 "In2.Cu" signal "L3")
		(8 "In3.Cu" signal "L4VCC")
		(10 "In4.Cu" signal "L5VCC")
		(12 "In5.Cu" signal "L6")
		(14 "In6.Cu" signal "L7GND")
		(2 "B.Cu" signal "BOTTOM")
		(9 "F.Adhes" user "F.Adhesive")
		(11 "B.Adhes" user "B.Adhesive")
		(13 "F.Paste" user "Package Geometry/Pastemask Top")
		(15 "B.Paste" user "Package Geometry/Pastemask Bottom")
		(5 "F.SilkS" user "Ref Des/Silkscreen Top")
		(7 "B.SilkS" user "Ref Des/Silkscreen Bottom")
		(1 "F.Mask" user "Board Geometry/Soldermask Top")
		(3 "B.Mask" user "Board Geometry/Soldermask Bottom")
		(17 "Dwgs.User" user "User.Drawings")
		(19 "Cmts.User" user "User.Comments")
		(21 "Eco1.User" user "User.Eco1")
		(23 "Eco2.User" user "User.Eco2")
		(25 "Edge.Cuts" user "Board Geometry/Outline")
		(27 "Margin" user)
		(31 "F.CrtYd" user "Package Geometry/Place Bound Top")
		(29 "B.CrtYd" user "Package Geometry/Place Bound Bottom")
		(35 "F.Fab" user "Ref Des/Assembly Top")
		(33 "B.Fab" user "Ref Des/Assembly Bottom")
	)
	(footprint ""
		(layer "F.Cu")
		(at 305.63439 -9.53008)
		(property "Reference" "CN16"
			(at 0 0 0)
			(layer "F.SilkS")
			(hide yes)
			(effects
				(font
					(size 1.27 1.27)
				)
			)
		)
		(property "Value" "MLX-CONN144-12R-3-GP-U2"
			(at -33.7693 -12.9032 0)
			(unlocked yes)
			(layer "F.Fab")
			(hide yes)
			(effects
				(font
					(size 1.016 1.016)
					(thickness 0.1524)
				)
			)
		)
		(property "Device Type" "PREFIT-144P-459383U2H519"
			(at -33.7693 -14.4272 0)
			(unlocked yes)
			(layer "F.Fab")
			(hide yes)
			(effects
				(font
					(size 1.016 1.016)
					(thickness 0.1524)
				)
			)
		)
		(duplicate_pad_numbers_are_jumpers no)
		(pad "PTH10" thru_hole circle
			(at 21.999956 -3.700018)
			(size 0.9144 0.9144)
			(drill 0.569976)
			(layers "*.Cu" "*.Mask")
			(remove_unused_layers no)
			(net "GND")
			(clearance 0.1905)
			(thermal_gap 0.1905)
		)
		(pad "PTH11" thru_hole circle
			(at 21.999956 9.61009)
			(size 0.9144 0.9144)
			(drill 0.569976)
			(layers "*.Cu" "*.Mask")
			(remove_unused_layers no)
			(net "GND")
			(clearance 0.1905)
			(thermal_gap 0.1905)
		)
		(pad "PTH12" thru_hole circle
			(at 10.999978 9.61009)
			(size 0.9144 0.9144)
			(drill 0.569976)
			(layers "*.Cu" "*.Mask")
			(remove_unused_layers no)
			(net "GND")
			(clearance 0.1905)
			(thermal_gap 0.1905)
		)
		(pad "PTH13" thru_hole circle
			(at 0 9.61009)
			(size 0.9144 0.9144)
			(drill 0.569976)
			(layers "*.Cu" "*.Mask")
			(remove_unused_layers no)
			(net "GND")
			(clearance 0.1905)
			(thermal_gap 0.1905)
		)
		(pad "PTH14" thru_hole circle
			(at -10.999978 9.61009)
			(size 0.9144 0.9144)
			(drill 0.569976)
			(layers "*.Cu" "*.Mask")
			(remove_unused_layers no)
			(net "GND")
			(clearance 0.1905)
			(thermal_gap 0.1905)
		)
		(pad "PTH15" thru_hole circle
			(at -21.999956 9.61009)
			(size 0.9144 0.9144)
			(drill 0.569976)
			(layers "*.Cu" "*.Mask")
			(remove_unused_layers no)
			(net "GND")
			(clearance 0.1905)
			(thermal_gap 0.1905)
		)
		(pad "PTH16" thru_hole circle
			(at -10.999978 -3.700018)
			(size 0.9144 0.9144)
			(drill 0.569976)
			(layers "*.Cu" "*.Mask")
			(remove_unused_layers no)
			(net "GND")
			(clearance 0.1905)
			(thermal_gap 0.1905)
		)
		(pad "PTH17" thru_hole circle
			(at 0 -3.700018)
			(size 0.9144 0.9144)
			(drill 0.569976)
			(layers "*.Cu" "*.Mask")
			(remove_unused_layers no)
			(net "GND")
			(clearance 0.1905)
			(thermal_gap 0.1905)
		)
		(pad "PTH18" thru_hole circle
			(at 10.999978 -3.700018)
			(size 0.9144 0.9144)
			(drill 0.569976)
			(layers "*.Cu" "*.Mask")
			(remove_unused_layers no)
			(net "GND")
			(clearance 0.1905)
			(thermal_gap 0.1905)
		)
		(pad "PTH19" thru_hole circle
			(at -16.500094 0)
			(size 2.6162 2.6162)
			(drill 2.2098)
			(layers "*.Cu" "*.Mask")
			(remove_unused_layers no)
			(net "GND")
			(clearance 0.3048)
			(thermal_gap 0.3048)
			(padstack
				(mode front_inner_back)
				(layer "Inner"
					(shape circle)
					(size 2.6162 2.6162)
					(clearance 0.3048)
				)
				(layer "B.Cu"
					(shape custom)
					(size 1.246578 1.246578)
					(options
						(anchor circle)
					)
					(primitives
						(gr_poly
							(pts
								(arc
									(start 0.300228 -2.49301)
									(mid 0 2.492801)
									(end -0.300228 -2.49301)
								)
								(arc
									(start -0.300228 -2.49301)
									(mid 0 -2.412041)
									(end 0.300228 -2.49301)
								)
							)
							(width 0)
							(fill yes)
						)
					)
					(clearance -0.889)
				)
			)
		)
		(pad "PTH20" thru_hole circle
			(at -5.500116 0)
			(size 2.6162 2.6162)
			(drill 2.2098)
			(layers "*.Cu" "*.Mask")
			(remove_unused_layers no)
			(net "GND")
			(clearance 0.3048)
			(thermal_gap 0.3048)
			(padstack
				(mode front_inner_back)
				(layer "Inner"
					(shape circle)
					(size 2.6162 2.6162)
					(clearance 0.3048)
				)
				(layer "B.Cu"
					(shape custom)
					(size 1.246578 1.246578)
					(options
						(anchor circle)
					)
					(primitives
						(gr_poly
							(pts
								(arc
									(start 0.300228 -2.49301)
									(mid 0 2.492801)
									(end -0.300228 -2.49301)
								)
								(arc
									(start -0.300228 -2.49301)
									(mid 0 -2.412041)
									(end 0.300228 -2.49301)
								)
							)
							(width 0)
							(fill yes)
						)
					)
					(clearance -0.889)
				)
			)
		)
		(pad "PTH21" thru_hole circle
			(at 5.500116 0)
			(size 2.6162 2.6162)
			(drill 2.2098)
			(layers "*.Cu" "*.Mask")
			(remove_unused_layers no)
			(net "GND")
			(clearance 0.3048)
			(thermal_gap 0.3048)
			(padstack
				(mode front_inner_back)
				(layer "Inner"
					(shape circle)
					(size 2.6162 2.6162)
					(clearance 0.3048)
				)
				(layer "B.Cu"
					(shape custom)
					(size 1.246578 1.246578)
					(options
						(anchor circle)
					)
					(primitives
						(gr_poly
							(pts
								(arc
									(start 0.300228 -2.49301)
									(mid 0 2.492801)
									(end -0.300228 -2.49301)
								)
								(arc
									(start -0.300228 -2.49301)
									(mid 0 -2.412041)
									(end 0.300228 -2.49301)
								)
							)
							(width 0)
							(fill yes)
						)
					)
					(clearance -0.889)
				)
			)
		)
		(pad "PTH22" thru_hole circle
			(at 16.500094 0)
			(size 2.6162 2.6162)
			(drill 2.2098)
			(layers "*.Cu" "*.Mask")
			(remove_unused_layers no)
			(net "GND")
			(clearance 0.3048)
			(thermal_gap 0.3048)
			(padstack
				(mode front_inner_back)
				(layer "Inner"
					(shape circle)
					(size 2.6162 2.6162)
					(clearance 0.3048)
				)
				(layer "B.Cu"
					(shape custom)
					(size 1.246578 1.246578)
					(options
						(anchor circle)
					)
					(primitives
						(gr_poly
							(pts
								(arc
									(start 0.300228 -2.49301)
									(mid 0 2.492801)
									(end -0.300228 -2.49301)
								)
								(arc
									(start -0.300228 -2.49301)
									(mid 0 -2.412041)
									(end 0.300228 -2.49301)
								)
							)
							(width 0)
							(fill yes)
						)
					)
					(clearance -0.889)
				)
			)
		)
	)
)
